(kicad_pcb
	(version 20241229)
	(generator "pcbnew")
	(generator_version "9.0")
	(general
		(thickness 1.61)
		(legacy_teardrops no)
	)
	(paper "A3")
	(title_block
		(title "SO-DIMM DDR5 Tester")
		(date "2025-11-26")
		(rev "1.3.0")
		(comment 9 "footprints 180-181 of 627")
	)
	(layers
		(0 "F.Cu" signal)
		(4 "In1.Cu" power)
		(6 "In2.Cu" mixed)
		(8 "In3.Cu" power)
		(10 "In4.Cu" mixed)
		(12 "In5.Cu" power)
		(14 "In6.Cu" mixed)
		(16 "In7.Cu" power)
		(18 "In8.Cu" power)
		(20 "In9.Cu" mixed)
		(22 "In10.Cu" power)
		(2 "B.Cu" signal)
		(9 "F.Adhes" user "F.Adhesive")
		(11 "B.Adhes" user "B.Adhesive")
		(13 "F.Paste" user)
		(15 "B.Paste" user)
		(5 "F.SilkS" user "F.Silkscreen")
		(7 "B.SilkS" user "B.Silkscreen")
		(1 "F.Mask" user)
		(3 "B.Mask" user)
		(17 "Dwgs.User" user "User.Drawings")
		(19 "Cmts.User" user "User.Comments")
		(21 "Eco1.User" user "User.Eco1")
		(23 "Eco2.User" user "User.Eco2")
		(25 "Edge.Cuts" user)
		(27 "Margin" user)
		(31 "F.CrtYd" user "F.Courtyard")
		(29 "B.CrtYd" user "B.Courtyard")
		(35 "F.Fab" user)
		(33 "B.Fab" user)
	)
	(footprint "antmicro-footprints:Edge_Conn_Bus_PCIexpress_x4"
		(layer "F.Cu")
		(at 114.525501 210.801)
		(descr "PCIexpress x4")
		(tags "PCIexpress")
		(property "Reference" "J9"
			(at -0.025 -3.175 0)
			(layer "F.SilkS")
			(effects
				(font
					(size 0.7 0.7)
					(thickness 0.15)
				)
				(justify left bottom)
			)
		)
		(property "Value" "Edge_Conn_Bus_PCIe_x4"
			(at -0.8 7.3 0)
			(layer "F.Fab")
			(effects
				(font
					(size 0.7 0.7)
					(thickness 0.15)
				)
				(justify left bottom)
			)
		)
		(property "Author" "Antmicro"
			(at 0 0 0)
			(layer "F.Fab")
			(hide yes)
			(effects
				(font
					(size 1 1)
					(thickness 0.15)
				)
			)
		)
		(property "License" "Apache-2.0"
			(at 0 0 0)
			(layer "F.Fab")
			(hide yes)
			(effects
				(font
					(size 1 1)
					(thickness 0.15)
				)
			)
		)
		(property "MPN" ""
			(at 0 0 0)
			(layer "F.Fab")
			(hide yes)
			(effects
				(font
					(size 1 1)
					(thickness 0.15)
				)
			)
		)
		(property "Manufacturer" ""
			(at 0 0 0)
			(layer "F.Fab")
			(hide yes)
			(effects
				(font
					(size 1 1)
					(thickness 0.15)
				)
			)
		)
		(sheetname "/PCIe connector/")
		(sheetfile "pcie-connector.kicad_sch")
		(attr exclude_from_pos_files exclude_from_bom)
		(fp_poly
			(pts
				(xy -0.85 -2) (xy 33.65 -2) (xy 33.65 3.5) (xy -0.85 3.5)
			)
			(stroke
				(width 0.2)
				(type solid)
			)
			(fill yes)
			(layer "F.Mask")
		)
		(fp_poly
			(pts
				(xy -0.85 -2) (xy 33.65 -2) (xy 33.65 3.5) (xy -0.85 3.5)
			)
			(stroke
				(width 0.2)
				(type solid)
			)
			(fill yes)
			(layer "B.Mask")
		)
		(fp_circle
			(center 0 -2.675)
			(end 0.05 -2.675)
			(stroke
				(width 0.15)
				(type solid)
			)
			(fill yes)
			(layer "F.SilkS")
		)
		(fp_line
			(start -0.65 -4.9)
			(end -0.65 3)
			(stroke
				(width 0.15)
				(type solid)
			)
			(layer "Edge.Cuts")
		)
		(fp_line
			(start -0.65 3)
			(end -0.15 3.5)
			(stroke
				(width 0.15)
				(type solid)
			)
			(layer "Edge.Cuts")
		)
		(fp_line
			(start -0.15 3.5)
			(end 10.05 3.5)
			(stroke
				(width 0.15)
				(type solid)
			)
			(layer "Edge.Cuts")
		)
		(fp_line
			(start 10.55 -3.95)
			(end 10.55 3)
			(stroke
				(width 0.15)
				(type solid)
			)
			(layer "Edge.Cuts")
		)
		(fp_line
			(start 10.55 3)
			(end 10.05 3.5)
			(stroke
				(width 0.15)
				(type solid)
			)
			(layer "Edge.Cuts")
		)
		(fp_line
			(start 12.45 -3.95)
			(end 12.45 3)
			(stroke
				(width 0.15)
				(type solid)
			)
			(layer "Edge.Cuts")
		)
		(fp_line
			(start 12.45 3)
			(end 12.95 3.5)
			(stroke
				(width 0.15)
				(type solid)
			)
			(layer "Edge.Cuts")
		)
		(fp_line
			(start 12.95 3.5)
			(end 33.15 3.5)
			(stroke
				(width 0.15)
				(type solid)
			)
			(layer "Edge.Cuts")
		)
		(fp_line
			(start 33.65 -4.9)
			(end 33.65 3)
			(stroke
				(width 0.15)
				(type solid)
			)
			(layer "Edge.Cuts")
		)
		(fp_line
			(start 33.65 3)
			(end 33.15 3.5)
			(stroke
				(width 0.15)
				(type solid)
			)
			(layer "Edge.Cuts")
		)
		(fp_arc
			(start 10.55 -3.95)
			(mid 11.5 -4.9)
			(end 12.45 -3.95)
			(stroke
				(width 0.15)
				(type solid)
			)
			(layer "Edge.Cuts")
		)
		(pad "A1" connect rect
			(at 0 -0.5)
			(size 0.7 3.2)
			(layers "B.Cu" "B.Mask")
			(net 229 "/PCIe connector/PRSNT#1")
			(pinfunction "~{PRSNT1}")
			(pintype "passive")
		)
		(pad "A2" connect rect
			(at 1 0)
			(size 0.7 4.2)
			(layers "B.Cu" "B.Mask")
			(net 11 "+12V")
			(pinfunction "12V")
			(pintype "power_out")
		)
		(pad "A3" connect rect
			(at 2 0)
			(size 0.7 4.2)
			(layers "B.Cu" "B.Mask")
			(net 11 "+12V")
			(pinfunction "12V")
			(pintype "passive")
		)
		(pad "A4" connect rect
			(at 3 0)
			(size 0.7 4.2)
			(layers "B.Cu" "B.Mask")
			(net 1 "GND")
			(pinfunction "GND")
			(pintype "passive")
		)
		(pad "A5" connect rect
			(at 4 0)
			(size 0.7 4.2)
			(layers "B.Cu" "B.Mask")
			(net 333 "unconnected-(J9-TCK-PadA5)")
			(pinfunction "TCK")
			(pintype "input+no_connect")
		)
		(pad "A6" connect rect
			(at 5 0)
			(size 0.7 4.2)
			(layers "B.Cu" "B.Mask")
			(net 334 "unconnected-(J9-TDI-PadA6)")
			(pinfunction "TDI")
			(pintype "input+no_connect")
		)
		(pad "A7" connect rect
			(at 6 0)
			(size 0.7 4.2)
			(layers "B.Cu" "B.Mask")
			(net 335 "unconnected-(J9-TDO-PadA7)")
			(pinfunction "TDO")
			(pintype "output+no_connect")
		)
		(pad "A8" connect rect
			(at 7 0)
			(size 0.7 4.2)
			(layers "B.Cu" "B.Mask")
			(net 336 "unconnected-(J9-TMS-PadA8)")
			(pinfunction "TMS")
			(pintype "input+no_connect")
		)
		(pad "A9" connect rect
			(at 8 0)
			(size 0.7 4.2)
			(layers "B.Cu" "B.Mask")
			(net 752 "unconnected-(J9-3V3-PadA10)_2")
			(pinfunction "3V3")
			(pintype "passive+no_connect")
		)
		(pad "A10" connect rect
			(at 9 0)
			(size 0.7 4.2)
			(layers "B.Cu" "B.Mask")
			(net 337 "unconnected-(J9-3V3-PadA10)")
			(pinfunction "3V3")
			(pintype "power_out+no_connect")
		)
		(pad "A11" connect rect
			(at 10 0)
			(size 0.7 4.2)
			(layers "B.Cu" "B.Mask")
			(net 135 "PCIE.PWRGD")
			(pinfunction "~{PERST}")
			(pintype "open_collector")
		)
		(pad "A12" connect rect
			(at 13 0)
			(size 0.7 4.2)
			(layers "B.Cu" "B.Mask")
			(net 1 "GND")
			(pinfunction "GND")
			(pintype "passive")
		)
		(pad "A13" connect rect
			(at 14 0)
			(size 0.7 4.2)
			(layers "B.Cu" "B.Mask")
			(net 12 "/FPGA MGT Interface/PCIE.CLK_P")
			(pinfunction "REFCLK_p")
			(pintype "input")
		)
		(pad "A14" connect rect
			(at 15 0)
			(size 0.7 4.2)
			(layers "B.Cu" "B.Mask")
			(net 14 "/FPGA MGT Interface/PCIE.CLK_N")
			(pinfunction "REFCLK_n")
			(pintype "input")
		)
		(pad "A15" connect rect
			(at 16 0)
			(size 0.7 4.2)
			(layers "B.Cu" "B.Mask")
			(net 1 "GND")
			(pinfunction "GND")
			(pintype "passive")
		)
		(pad "A16" connect rect
			(at 17 0)
			(size 0.7 4.2)
			(layers "B.Cu" "B.Mask")
			(net 22 "/FPGA MGT Interface/PCIE.TXD0_P")
			(pinfunction "HSI0_p")
			(pintype "output")
		)
		(pad "A17" connect rect
			(at 18 0)
			(size 0.7 4.2)
			(layers "B.Cu" "B.Mask")
			(net 28 "/FPGA MGT Interface/PCIE.TXD0_N")
			(pinfunction "HSI0_n")
			(pintype "output")
		)
		(pad "A18" connect rect
			(at 19 0)
			(size 0.7 4.2)
			(layers "B.Cu" "B.Mask")
			(net 1 "GND")
			(pinfunction "GND")
			(pintype "passive")
		)
		(pad "A19" connect rect
			(at 20 0)
			(size 0.7 4.2)
			(layers "B.Cu" "B.Mask")
			(net 338 "unconnected-(J9-NC-PadA19)")
			(pinfunction "NC")
			(pintype "no_connect")
		)
		(pad "A20" connect rect
			(at 21 0)
			(size 0.7 4.2)
			(layers "B.Cu" "B.Mask")
			(net 1 "GND")
			(pinfunction "GND")
			(pintype "passive")
		)
		(pad "A21" connect rect
			(at 22 0)
			(size 0.7 4.2)
			(layers "B.Cu" "B.Mask")
			(net 20 "/FPGA MGT Interface/PCIE.TXD1_P")
			(pinfunction "HSI1_p")
			(pintype "output")
		)
		(pad "A22" connect rect
			(at 23 0)
			(size 0.7 4.2)
			(layers "B.Cu" "B.Mask")
			(net 31 "/FPGA MGT Interface/PCIE.TXD1_N")
			(pinfunction "HSI1_n")
			(pintype "output")
		)
		(pad "A23" connect rect
			(at 24 0)
			(size 0.7 4.2)
			(layers "B.Cu" "B.Mask")
			(net 1 "GND")
			(pinfunction "GND")
			(pintype "passive")
		)
		(pad "A24" connect rect
			(at 25 0)
			(size 0.7 4.2)
			(layers "B.Cu" "B.Mask")
			(net 1 "GND")
			(pinfunction "GND")
			(pintype "passive")
		)
		(pad "A25" connect rect
			(at 26 0)
			(size 0.7 4.2)
			(layers "B.Cu" "B.Mask")
			(net 18 "/FPGA MGT Interface/PCIE.TXD2_P")
			(pinfunction "HSI2_p")
			(pintype "output")
		)
		(pad "A26" connect rect
			(at 27 0)
			(size 0.7 4.2)
			(layers "B.Cu" "B.Mask")
			(net 26 "/FPGA MGT Interface/PCIE.TXD2_N")
			(pinfunction "HSI2_n")
			(pintype "output")
		)
		(pad "A27" connect rect
			(at 28 0)
			(size 0.7 4.2)
			(layers "B.Cu" "B.Mask")
			(net 1 "GND")
			(pinfunction "GND")
			(pintype "passive")
		)
		(pad "A28" connect rect
			(at 29 0)
			(size 0.7 4.2)
			(layers "B.Cu" "B.Mask")
			(net 1 "GND")
			(pinfunction "GND")
			(pintype "passive")
		)
		(pad "A29" connect rect
			(at 30 0)
			(size 0.7 4.2)
			(layers "B.Cu" "B.Mask")
			(net 16 "/FPGA MGT Interface/PCIE.TXD3_P")
			(pinfunction "HSI3_p")
			(pintype "output")
		)
		(pad "A30" connect rect
			(at 31 0)
			(size 0.7 4.2)
			(layers "B.Cu" "B.Mask")
			(net 24 "/FPGA MGT Interface/PCIE.TXD3_N")
			(pinfunction "HSI3_n")
			(pintype "output")
		)
		(pad "A31" connect rect
			(at 32 0)
			(size 0.7 4.2)
			(layers "B.Cu" "B.Mask")
			(net 1 "GND")
			(pinfunction "GND")
			(pintype "passive")
		)
		(pad "A32" connect rect
			(at 33 0)
			(size 0.7 4.2)
			(layers "B.Cu" "B.Mask")
			(net 339 "unconnected-(J9-NC-PadA32)")
			(pinfunction "NC")
			(pintype "no_connect")
		)
		(pad "B1" connect rect
			(at 0 0)
			(size 0.7 4.2)
			(layers "F.Cu" "F.Mask")
			(net 11 "+12V")
			(pinfunction "12V")
			(pintype "passive")
		)
		(pad "B2" connect rect
			(at 1 0)
			(size 0.7 4.2)
			(layers "F.Cu" "F.Mask")
			(net 11 "+12V")
			(pinfunction "12V")
			(pintype "passive")
		)
		(pad "B3" connect rect
			(at 2 0)
			(size 0.7 4.2)
			(layers "F.Cu" "F.Mask")
			(net 11 "+12V")
			(pinfunction "12V")
			(pintype "passive")
		)
		(pad "B4" connect rect
			(at 3 0)
			(size 0.7 4.2)
			(layers "F.Cu" "F.Mask")
			(net 1 "GND")
			(pinfunction "GND")
			(pintype "passive")
		)
		(pad "B5" connect rect
			(at 4 0)
			(size 0.7 4.2)
			(layers "F.Cu" "F.Mask")
			(net 340 "unconnected-(J9-SMCLK-PadB5)")
			(pinfunction "SMCLK")
			(pintype "open_collector+no_connect")
		)
		(pad "B6" connect rect
			(at 5 0)
			(size 0.7 4.2)
			(layers "F.Cu" "F.Mask")
			(net 341 "unconnected-(J9-SMDAT-PadB6)")
			(pinfunction "SMDAT")
			(pintype "open_collector+no_connect")
		)
		(pad "B7" connect rect
			(at 6 0)
			(size 0.7 4.2)
			(layers "F.Cu" "F.Mask")
			(net 1 "GND")
			(pinfunction "GND")
			(pintype "passive")
		)
		(pad "B8" connect rect
			(at 7 0)
			(size 0.7 4.2)
			(layers "F.Cu" "F.Mask")
			(net 715 "unconnected-(J9-3V3-PadA10)_1")
			(pinfunction "3V3")
			(pintype "passive+no_connect")
		)
		(pad "B9" connect rect
			(at 8 0)
			(size 0.7 4.2)
			(layers "F.Cu" "F.Mask")
			(net 342 "unconnected-(J9-~{TRST}-PadB9)")
			(pinfunction "~{TRST}")
			(pintype "input+no_connect")
		)
		(pad "B10" connect rect
			(at 9 0)
			(size 0.7 4.2)
			(layers "F.Cu" "F.Mask")
			(net 343 "unconnected-(J9-3V3AUX-PadB10)")
			(pinfunction "3V3AUX")
			(pintype "power_out+no_connect")
		)
		(pad "B11" connect rect
			(at 10 0)
			(size 0.7 4.2)
			(layers "F.Cu" "F.Mask")
			(net 344 "unconnected-(J9-~{WAKE}-PadB11)")
			(pinfunction "~{WAKE}")
			(pintype "open_collector+no_connect")
		)
		(pad "B12" connect rect
			(at 13 0)
			(size 0.7 4.2)
			(layers "F.Cu" "F.Mask")
			(net 345 "unconnected-(J9-~{CLKREQ}-PadB12)")
			(pinfunction "~{CLKREQ}")
			(pintype "open_collector+no_connect")
		)
		(pad "B13" connect rect
			(at 14 0)
			(size 0.7 4.2)
			(layers "F.Cu" "F.Mask")
			(net 1 "GND")
			(pinfunction "GND")
			(pintype "passive")
		)
		(pad "B14" connect rect
			(at 15 0)
			(size 0.7 4.2)
			(layers "F.Cu" "F.Mask")
			(net 604 "/FPGA MGT Interface/PCIE.RXD0_P")
			(pinfunction "HSO0_p")
			(pintype "input")
		)
		(pad "B15" connect rect
			(at 16 0)
			(size 0.7 4.2)
			(layers "F.Cu" "F.Mask")
			(net 605 "/FPGA MGT Interface/PCIE.RXD0_N")
			(pinfunction "HSO0_n")
			(pintype "input")
		)
		(pad "B16" connect rect
			(at 17 0)
			(size 0.7 4.2)
			(layers "F.Cu" "F.Mask")
			(net 1 "GND")
			(pinfunction "GND")
			(pintype "passive")
		)
		(pad "B17" connect rect
			(at 18 -0.5)
			(size 0.7 3.2)
			(layers "F.Cu" "F.Mask")
			(net 230 "/PCIe connector/x1")
			(pinfunction "~{PRSNT2_x1}")
			(pintype "passive")
		)
		(pad "B18" connect rect
			(at 19 0)
			(size 0.7 4.2)
			(layers "F.Cu" "F.Mask")
			(net 1 "GND")
			(pinfunction "GND")
			(pintype "passive")
		)
		(pad "B19" connect rect
			(at 20 0)
			(size 0.7 4.2)
			(layers "F.Cu" "F.Mask")
			(net 606 "/FPGA MGT Interface/PCIE.RXD1_P")
			(pinfunction "HSO1_p")
			(pintype "input")
		)
		(pad "B20" connect rect
			(at 21 0)
			(size 0.7 4.2)
			(layers "F.Cu" "F.Mask")
			(net 607 "/FPGA MGT Interface/PCIE.RXD1_N")
			(pinfunction "HSO1_n")
			(pintype "input")
		)
		(pad "B21" connect rect
			(at 22 0)
			(size 0.7 4.2)
			(layers "F.Cu" "F.Mask")
			(net 1 "GND")
			(pinfunction "GND")
			(pintype "passive")
		)
		(pad "B22" connect rect
			(at 23 0)
			(size 0.7 4.2)
			(layers "F.Cu" "F.Mask")
			(net 1 "GND")
			(pinfunction "GND")
			(pintype "passive")
		)
		(pad "B23" connect rect
			(at 24 0)
			(size 0.7 4.2)
			(layers "F.Cu" "F.Mask")
			(net 608 "/FPGA MGT Interface/PCIE.RXD2_P")
			(pinfunction "HSO2_p")
			(pintype "input")
		)
		(pad "B24" connect rect
			(at 25 0)
			(size 0.7 4.2)
			(layers "F.Cu" "F.Mask")
			(net 609 "/FPGA MGT Interface/PCIE.RXD2_N")
			(pinfunction "HSO2_n")
			(pintype "input")
		)
		(pad "B25" connect rect
			(at 26 0)
			(size 0.7 4.2)
			(layers "F.Cu" "F.Mask")
			(net 1 "GND")
			(pinfunction "GND")
			(pintype "passive")
		)
		(pad "B26" connect rect
			(at 27 0)
			(size 0.7 4.2)
			(layers "F.Cu" "F.Mask")
			(net 1 "GND")
			(pinfunction "GND")
			(pintype "passive")
		)
		(pad "B27" connect rect
			(at 28 0)
			(size 0.7 4.2)
			(layers "F.Cu" "F.Mask")
			(net 610 "/FPGA MGT Interface/PCIE.RXD3_P")
			(pinfunction "HSO3_p")
			(pintype "input")
		)
		(pad "B28" connect rect
			(at 29 0)
			(size 0.7 4.2)
			(layers "F.Cu" "F.Mask")
			(net 611 "/FPGA MGT Interface/PCIE.RXD3_N")
			(pinfunction "HSO3_n")
			(pintype "input")
		)
		(pad "B29" connect rect
			(at 30 0)
			(size 0.7 4.2)
			(layers "F.Cu" "F.Mask")
			(net 1 "GND")
			(pinfunction "GND")
			(pintype "passive")
		)
		(pad "B30" connect rect
			(at 31 0)
			(size 0.7 4.2)
			(layers "F.Cu" "F.Mask")
			(net 346 "unconnected-(J9-~{PWRBRK}-PadB30)")
			(pinfunction "~{PWRBRK}")
			(pintype "open_collector+no_connect")
		)
		(pad "B31" connect rect
			(at 32 -0.5)
			(size 0.7 3.2)
			(layers "F.Cu" "F.Mask")
			(net 231 "/PCIe connector/x4")
			(pinfunction "~{PRSNT2_x4}")
			(pintype "passive")
		)
		(pad "B32" connect rect
			(at 33 0)
			(size 0.7 4.2)
			(layers "F.Cu" "F.Mask")
			(net 1 "GND")
			(pinfunction "GND")
			(pintype "passive")
		)
	)
	(footprint "antmicro-footprints:R_0402_1005Metric"
		(layer "F.Cu")
		(at 99.423 132.981)
		(descr "Resistor SMD 0402")
		(tags "resistor SMD 0402")
		(property "Reference" "R126"
			(at -4.154968 0.309606 0)
			(layer "F.SilkS")
			(effects
				(font
					(size 0.7 0.7)
					(thickness 0.15)
				)
				(justify left bottom)
			)
		)
		(property "Value" "R_0R_0402"
			(at -1.011843 1.772047 0)
			(layer "F.Fab")
			(effects
				(font
					(size 0.7 0.7)
					(thickness 0.15)
				)
				(justify left bottom)
			)
		)
		(property "Datasheet" "https://industrial.panasonic.com/cdbs/www-data/pdf/RDA0000/AOA0000C301.pdf"
			(at 0 0 0)
			(layer "F.Fab")
			(hide yes)
			(effects
				(font
					(size 1.27 1.27)
					(thickness 0.15)
				)
			)
		)
		(property "Author" "Antmicro"
			(at 0 0 0)
			(layer "F.Fab")
			(hide yes)
			(effects
				(font
					(size 1 1)
					(thickness 0.15)
				)
			)
		)
		(property "Current" "1A"
			(at 0 0 0)
			(layer "F.Fab")
			(hide yes)
			(effects
				(font
					(size 1 1)
					(thickness 0.15)
				)
			)
		)
		(property "License" "Apache-2.0"
			(at 0 0 0)
			(layer "F.Fab")
			(hide yes)
			(effects
				(font
					(size 1 1)
					(thickness 0.15)
				)
			)
		)
		(property "MPN" "ERJ2GE0R00X"
			(at 0 0 0)
			(layer "F.Fab")
			(hide yes)
			(effects
				(font
					(size 1 1)
					(thickness 0.15)
				)
			)
		)
		(property "Manufacturer" "Panasonic"
			(at 0 0 0)
			(layer "F.Fab")
			(hide yes)
			(effects
				(font
					(size 1 1)
					(thickness 0.15)
				)
			)
		)
		(property "Tolerance" ""
			(at 0 0 0)
			(layer "F.Fab")
			(hide yes)
			(effects
				(font
					(size 1 1)
					(thickness 0.15)
				)
			)
		)
		(property "Val" "0R"
			(at 0 0 0)
			(layer "F.Fab")
			(hide yes)
			(effects
				(font
					(size 1 1)
					(thickness 0.15)
				)
			)
		)
		(sheetname "/I^{2}C/")
		(sheetfile "i2c.kicad_sch")
		(attr exclude_from_pos_files exclude_from_bom dnp)
		(fp_rect
			(start -0.93 -0.47)
			(end 0.93 0.47)
			(stroke
				(width 0.05)
				(type solid)
			)
			(fill no)
			(layer "F.CrtYd")
		)
		(fp_rect
			(start -0.5 -0.25)
			(end 0.5 0.25)
			(stroke
				(width 0.15)
				(type solid)
			)
			(fill no)
			(layer "F.Fab")
		)
		(pad "1" smd roundrect
			(at -0.485 0)
			(size 0.59 0.64)
			(layers "F.Cu" "F.Mask" "F.Paste")
			(roundrect_rratio 0.25)
			(net 227 "+1V0")
			(pintype "passive")
		)
		(pad "2" smd roundrect
			(at 0.485 0)
			(size 0.59 0.64)
			(layers "F.Cu" "F.Mask" "F.Paste")
			(roundrect_rratio 0.25)
			(net 267 "VDDSPD")
			(pintype "passive")
		)
	)
)
